FILE_TYPE = CONNECTIVITY;
{Allegro Design Entry HDL 16.6-p007 (v16-6-112F) 10/10/2012}
"PAGE_NUMBER" = 115;
0"NC";
1"GND\g";
2"GND\g";
3"TP_USB3_P02_RXP";
4"USB2_P02_DN_R";
5"USB2_PCH_BMC_P5_DP_R";
6"TP_USB3_P02_RXN";
7"TP_USB3_P04_RXP";
8"USB2_P01_DN";
9"USB2_P02_DN";
10"USB2_P01_DP";
11"USB2_P02_DP";
12"USB_PCH_BMC_P4_DN";
13"TP_USB2_P03_DN";
14"TP_USB2_P03_DP";
15"USB_PCH_BMC_P4_DP";
16"TP_USB2_P06_DN";
17"TP_USB2_P06_DP";
18"USB2_PCH_BMC_P5_DN";
19"USB2_PCH_BMC_P5_DN_R";
20"USB2_PCH_BMC_P5_DP";
21"TP_USB2_P8_DP";
22"TP_USB2_P9_DN";
23"A_USB2_COMP";
24"TP_USB3_P06_TXN";
25"TP_USB3_P05_RXN";
26"USB3_P01_RXN";
27"A_USB2_VBUS";
28"USB2_P02_DP_R";
29"TP_USB2_P07_DP";
30"TP_USB2_P8_DN";
31"TP_USB2_P9_DP";
32"TP_USB2_P12_DN";
33"TP_USB2_P11_DP";
34"USB_PCH_BMC_P4_DP_R";
35"USB_PCH_BMC_P4_DN_R";
36"TP_USB2_P11_DN";
37"USB3_P01_RXP";
38"TP_USB3_P03_RXN";
39"TP_USB3_P03_RXP";
40"TP_USB3_P05_RXP";
41"TP_USB3_P06_RXP";
42"TP_USB2_P14_DP";
43"TP_USB2_P14_DN";
44"TP_USB2_P13_DP";
45"TP_USB3_P04_RXN";
46"TP_USB3_P06_RXN";
47"USB3_P01_TXN";
48"USB3_P01_TXP";
49"TP_USB2_P13_DN";
50"TP_USB2_P10_DN";
51"TP_USB3_P02_TXN";
52"TP_USB3_P03_TXP";
53"TP_USB3_P04_TXN";
54"TP_USB3_P03_TXN";
55"TP_USB3_P02_TXP";
56"TP_USB2_P12_DP";
57"TP_USB3_P05_TXN";
58"TP_USB3_P05_TXP";
59"TP_USB3_P06_TXP";
60"TP_USB3_P04_TXP";
61"TP_USB2_P07_DN";
62"TP_USB2_P10_DP";
63"TP_PCH_RSVD55";
%"RES"
"2","(-5425,1775)","0","mstr_discrete","I114";
;
CDS_SEC"1"
CDS_LOCATION"R8B32"
LOCATION"R8B32"
WATTAGE"1/16W"
TOLERANCE"1%"
VALUE"10.0K"
MATERIAL"CHIP"
PART_NUMBER"G21796-016"
PACK_TYPE"0402"
SEC"1"
CDS_LIB"mstr_discrete"
SEC_TYPE"0402";
"A"
$PN"1"27;
"B"
$PN"2"1;
%"GND"
"1","(-5425,1550)","0","mstr_symbols","I115";
;
HDL_POWER"GND"
BODY_TYPE"PLUMBING"
VOLTAGE"0.0V"
CDS_LIB"mstr_symbols"
SIZE"1B";
"A\NAC"1;
%"RES"
"1","(-2150,1950)","0","mstr_discrete","I118";
;
CDS_SEC"1"
CDS_LOCATION"R1W14"
TOLERANCE"5%"
LOCATION"R1W14"
PART_NUMBER"G21497-005"
VALUE"0.0"
MATERIAL"CHIP"
WATTAGE"1/16W"
PACK_TYPE"0402"
SEC"1"
SEC_TYPE"0402"
BOM_COST"SM_CONTROLLER"
ROOM"BMC"
CDS_LIB"mstr_discrete";
"B"
$PN"2"20;
"A"
$PN"1"5;
%"RES"
"1","(-2150,1900)","0","mstr_discrete","I119";
;
CDS_SEC"1"
CDS_LOCATION"R1W15"
WATTAGE"1/16W"
LOCATION"R1W15"
TOLERANCE"5%"
VALUE"0.0"
PART_NUMBER"G21497-005"
MATERIAL"CHIP"
PACK_TYPE"0402"
SEC"1"
SEC_TYPE"0402"
CDS_LIB"mstr_discrete"
BOM_COST"SM_CONTROLLER"
ROOM"BMC";
"B"
$PN"2"18;
"A"
$PN"1"19;
%"RES"
"1","(-2150,1800)","0","mstr_discrete","I120";
;
CDS_SEC"1"
CDS_LOCATION"R1W17"
LOCATION"R1W17"
WATTAGE"1/16W"
TOLERANCE"5%"
VALUE"0.0"
PACK_TYPE"0402"
MATERIAL"CHIP"
PART_NUMBER"G21497-005"
SEC"1"
SEC_TYPE"0402"
CDS_LIB"mstr_discrete"
BOM_COST"SM_CONTROLLER"
ROOM"BMC";
"B"
$PN"2"12;
"A"
$PN"1"35;
%"RES"
"1","(-2150,1850)","0","mstr_discrete","I121";
;
CDS_SEC"1"
CDS_LOCATION"R1W16"
TOLERANCE"5%"
LOCATION"R1W16"
WATTAGE"1/16W"
PART_NUMBER"G21497-005"
VALUE"0.0"
MATERIAL"CHIP"
PACK_TYPE"0402"
SEC"1"
SEC_TYPE"0402"
BOM_COST"SM_CONTROLLER"
ROOM"BMC"
CDS_LIB"mstr_discrete";
"B"
$PN"2"15;
"A"
$PN"1"34;
%"RES"
"1","(-2150,1600)","0","mstr_discrete","I122";
;
CDS_SEC"1"
CDS_LOCATION"R1W19"
VALUE"0.0"
MATERIAL"CHIP"
TOLERANCE"5%"
PART_NUMBER"G21497-005"
LOCATION"R1W19"
PACK_TYPE"0402"
WATTAGE"1/16W"
SEC"1"
SEC_TYPE"0402"
CDS_LIB"mstr_discrete"
BOM_COST"SM_CONTROLLER"
ROOM"BMC";
"B"
$PN"2"9;
"A"
$PN"1"4;
%"RES"
"1","(-2150,1650)","0","mstr_discrete","I123";
;
CDS_SEC"1"
CDS_LOCATION"R1W18"
TOLERANCE"5%"
PART_NUMBER"G21497-005"
LOCATION"R1W18"
PACK_TYPE"0402"
WATTAGE"1/16W"
MATERIAL"CHIP"
VALUE"0.0"
SEC"1"
SEC_TYPE"0402"
BOM_COST"SM_CONTROLLER"
ROOM"BMC"
CDS_LIB"mstr_discrete";
"B"
$PN"2"11;
"A"
$PN"1"28;
%"LBG_CORE_QAT_EXT_D"
"2","(-4000,2500)","0","mstr_u_proc","I74";
;
CDS_SEC"2"
PART_NUMBER"H91415-002"
LOCATION"U7C1"
MATERIAL"IC"
PACK_TYPE"BGA1"
SEC_TYPE"BGA1"
SEC"2"
CDS_LIB"mstr_u_proc"
BOM_COST"SB"
CDS_LOCATION"U7C1"
ROOM"SB";
"USB3_6_TXP"
$PN"BM61"59;
"USB3_6_TXN"
$PN"BL59"24;
"USB3_6_RXP"
$PN"BD70"41;
"USB3_6_RXN"
$PN"BD72"46;
"USB3_5_TXP"
$PN"BJ59"58;
"USB3_5_TXN"
$PN"BK58"57;
"USB3_5_RXP"
$PN"BE69"40;
"USB3_5_RXN"
$PN"BE71"25;
"USB3_4_TXP"
$PN"BG56"60;
"USB3_4_TXN"
$PN"BH58"53;
"USB3_4_RXP"
$PN"BF70"7;
"USB3_4_RXN"
$PN"BF72"45;
"USB3_3_TXP"
$PN"BN56"52;
"USB3_3_TXN"
$PN"BM54"54;
"USB3_3_RXP"
$PN"BH69"39;
"USB3_3_RXN"
$PN"BH71"38;
"USB3_2_TXP"
$PN"BJ56"55;
"USB3_2_TXN"
$PN"BL56"51;
"USB3_2_RXP"
$PN"BJ70"3;
"USB3_2_RXN"
$PN"BJ72"6;
"USB3_1_TXP"
$PN"BK54"48;
"USB3_1_TXN"
$PN"BL52"47;
"USB3_1_RXP"
$PN"BK69"37;
"USB3_1_RXN"
$PN"BK71"26;
"USB2_VBUS"
$PN"BR67"27;
"USB2_COMP"
$PN"BN70"23;
"USB2P_9"
$PN"BV55"31;
"USB2P_8"
$PN"BV64"21;
"USB2P_7"
$PN"BW57"29;
"USB2P_6"
$PN"BW63"17;
"USB2P_5"
$PN"BV58"5;
"USB2P_4"
$PN"BV62"34;
"USB2P_3"
$PN"BW59"14;
"USB2P_2"
$PN"BW61"28;
"USB2P_14"
$PN"BU67"42;
"USB2P_13"
$PN"BV53"44;
"USB2P_12"
$PN"BV66"56;
"USB2P_11"
$PN"BW54"33;
"USB2P_10"
$PN"BU65"62;
"USB2P_1"
$PN"BV60"10;
"USB2N_9"
$PN"BY55"22;
"USB2N_8"
$PN"BY64"30;
"USB2N_7"
$PN"CA57"61;
"USB2N_6"
$PN"CA63"16;
"USB2N_5"
$PN"BY58"19;
"USB2N_4"
$PN"BY62"35;
"USB2N_3"
$PN"CA59"13;
"USB2N_2"
$PN"CA61"4;
"USB2N_14"
$PN"BW68"43;
"USB2N_13"
$PN"BY53"49;
"USB2N_12"
$PN"BW67"32;
"USB2N_11"
$PN"CA54"36;
"USB2N_10"
$PN"BW65"50;
"USB2N_1"
$PN"BY60"8;
"RSVD<55>"
$PN"BN68"63;
%"RES"
"2","(-5750,1775)","0","mstr_discrete","I90";
;
CDS_SEC"1"
MATERIAL"CHIP"
PART_NUMBER"G21796-341"
PACK_TYPE"0402"
LOCATION"R8B9"
WATTAGE"1/16W"
TOLERANCE"1%"
VALUE"113"
CDS_LOCATION"R8B9"
SEC"1"
SEC_TYPE"0402"
CDS_LIB"mstr_discrete"
ROOM"SB";
"A"
$PN"1"23;
"B"
$PN"2"2;
%"GND"
"1","(-5750,1550)","0","mstr_symbols","I91";
;
HDL_POWER"GND"
BODY_TYPE"PLUMBING"
VOLTAGE"0.0V"
SIZE"1B"
CDS_LIB"mstr_symbols";
"A\NAC"2;
END.
